# T6G (Grand Teton) — schematic netlist excerpt (pin names and nets, part order shuffled) for the footprints in the layout excerpt that follows; sources: Cadence DE-HDL packaged netlist, KiCad conversion of 04192023_DAF0TMB3IC0_F0TG_MB_C_brd_V02_OCP.brd

R1312  Q_RES  0 5% CHIP  pkg 0402LF  page 252 : A = SMB_ADC_SDA ; B = SMB_ADC_SDA_R
R1551  Q_RES  33 5% CHIP  pkg 0402LF  page 81 : A = ESPI_CPU0_R1_D2 ; B = ESPI_CPU0_D2

(kicad_pcb
	(version 20260206)
	(generator "pcbnew")
	(generator_version "10.0")
	(general
		(thickness 1.6)
		(legacy_teardrops no)
	)
	(paper "A4")
	(title_block
		(title "04192023_DAF0TMB3IC0_F0TG_MB_C_brd_V02_OCP.brd")
		(comment 1 "Grand Teton / footprints 615-616 of 8354")
	)
	(layers
		(0 "F.Cu" signal "TOP")
		(4 "In1.Cu" signal "GND")
		(6 "In2.Cu" signal "IN1")
		(8 "In3.Cu" signal "GND1")
		(10 "In4.Cu" signal "IN2")
		(12 "In5.Cu" signal "GND2")
		(14 "In6.Cu" signal "IN3")
		(16 "In7.Cu" signal "GND3")
		(18 "In8.Cu" signal "VCC")
		(20 "In9.Cu" signal "VCC1")
		(22 "In10.Cu" signal "GND4")
		(24 "In11.Cu" signal "IN4")
		(26 "In12.Cu" signal "GND5")
		(28 "In13.Cu" signal "IN5")
		(30 "In14.Cu" signal "GND6")
		(32 "In15.Cu" signal "IN6")
		(34 "In16.Cu" signal "GND7")
		(2 "B.Cu" signal "BOTTOM")
		(9 "F.Adhes" user "F.Adhesive")
		(11 "B.Adhes" user "B.Adhesive")
		(13 "F.Paste" user "Package Geometry/Pastemask Top")
		(15 "B.Paste" user "Package Geometry/Pastemask Bottom")
		(5 "F.SilkS" user "Ref Des/Silkscreen Top")
		(7 "B.SilkS" user "Ref Des/Silkscreen Bottom")
		(1 "F.Mask" user "Board Geometry/Soldermask Top")
		(3 "B.Mask" user "Board Geometry/Soldermask Bottom")
		(17 "Dwgs.User" user "User.Drawings")
		(19 "Cmts.User" user "User.Comments")
		(21 "Eco1.User" user "User.Eco1")
		(23 "Eco2.User" user "User.Eco2")
		(25 "Edge.Cuts" user "Board Geometry/Outline")
		(27 "Margin" user)
		(31 "F.CrtYd" user "Package Geometry/Place Bound Top")
		(29 "B.CrtYd" user "Package Geometry/Place Bound Bottom")
		(35 "F.Fab" user "Ref Des/Assembly Top")
		(33 "B.Fab" user "Ref Des/Assembly Bottom")
	)
	(footprint ""
		(layer "F.Cu")
		(at 188.087 -137.632948 -90)
		(property "Reference" "R1551"
			(at 0 0 270)
			(layer "F.SilkS")
			(hide yes)
			(effects
				(font
					(size 1.27 1.27)
				)
			)
		)
		(property "Value" ""
			(at 0 0 270)
			(layer "F.Fab")
			(effects
				(font
					(size 1.27 1.27)
				)
			)
		)
		(duplicate_pad_numbers_are_jumpers no)
		(fp_line
			(start -0.7874 0.4064)
			(end -0.7874 -0.4064)
			(stroke
				(width 0.1524)
				(type default)
			)
			(layer "F.SilkS")
		)
		(fp_line
			(start 0.7874 0.4064)
			(end -0.7874 0.4064)
			(stroke
				(width 0.1524)
				(type default)
			)
			(layer "F.SilkS")
		)
		(fp_line
			(start -0.7874 -0.4064)
			(end 0.7874 -0.4064)
			(stroke
				(width 0.1524)
				(type default)
			)
			(layer "F.SilkS")
		)
		(fp_line
			(start 0.7874 -0.4064)
			(end 0.7874 0.4064)
			(stroke
				(width 0.1524)
				(type default)
			)
			(layer "F.SilkS")
		)
		(fp_line
			(start -0.67945 0.3048)
			(end -0.67945 -0.305054)
			(stroke
				(width 0.1)
				(type default)
			)
			(layer "F.Fab")
		)
		(fp_line
			(start -0.12065 0.3048)
			(end -0.67945 0.3048)
			(stroke
				(width 0.1)
				(type default)
			)
			(layer "F.Fab")
		)
		(fp_line
			(start 0.120396 0.3048)
			(end 0.120396 0.2794)
			(stroke
				(width 0.1)
				(type default)
			)
			(layer "F.Fab")
		)
		(fp_line
			(start 0.67945 0.3048)
			(end 0.120396 0.3048)
			(stroke
				(width 0.1)
				(type default)
			)
			(layer "F.Fab")
		)
		(fp_line
			(start -0.12065 0.2794)
			(end -0.12065 0.3048)
			(stroke
				(width 0.1)
				(type default)
			)
			(layer "F.Fab")
		)
		(fp_line
			(start 0.120396 0.2794)
			(end -0.12065 0.2794)
			(stroke
				(width 0.1)
				(type default)
			)
			(layer "F.Fab")
		)
		(fp_line
			(start -0.12065 -0.2794)
			(end 0.12065 -0.2794)
			(stroke
				(width 0.1)
				(type default)
			)
			(layer "F.Fab")
		)
		(fp_line
			(start 0.12065 -0.2794)
			(end 0.12065 -0.3048)
			(stroke
				(width 0.1)
				(type default)
			)
			(layer "F.Fab")
		)
		(fp_line
			(start 0.12065 -0.3048)
			(end 0.67945 -0.3048)
			(stroke
				(width 0.1)
				(type default)
			)
			(layer "F.Fab")
		)
		(fp_line
			(start 0.67945 -0.3048)
			(end 0.67945 0.3048)
			(stroke
				(width 0.1)
				(type default)
			)
			(layer "F.Fab")
		)
		(fp_line
			(start -0.67945 -0.305054)
			(end -0.12065 -0.305054)
			(stroke
				(width 0.1)
				(type default)
			)
			(layer "F.Fab")
		)
		(fp_line
			(start -0.12065 -0.305054)
			(end -0.12065 -0.2794)
			(stroke
				(width 0.1)
				(type default)
			)
			(layer "F.Fab")
		)
		(pad "1" smd circle
			(at -0.40005 0 270)
			(size 0 0)
			(layers "F.Cu" "F.Mask" "F.Paste")
			(net "ESPI_CPU0_R1_D2")
		)
		(pad "2" smd circle
			(at 0.40005 0 270)
			(size 0 0)
			(layers "F.Cu" "F.Mask" "F.Paste")
			(net "ESPI_CPU0_D2")
		)
	)
	(footprint ""
		(layer "F.Cu")
		(at 271.092676 -118.618)
		(property "Reference" "R1312"
			(at 0 0 0)
			(layer "F.SilkS")
			(hide yes)
			(effects
				(font
					(size 1.27 1.27)
				)
			)
		)
		(property "Value" ""
			(at 0 0 0)
			(layer "F.Fab")
			(effects
				(font
					(size 1.27 1.27)
				)
			)
		)
		(duplicate_pad_numbers_are_jumpers no)
		(fp_line
			(start -0.7874 -0.4064)
			(end 0.7874 -0.4064)
			(stroke
				(width 0.1524)
				(type default)
			)
			(layer "F.SilkS")
		)
		(fp_line
			(start -0.7874 0.4064)
			(end -0.7874 -0.4064)
			(stroke
				(width 0.1524)
				(type default)
			)
			(layer "F.SilkS")
		)
		(fp_line
			(start 0.7874 -0.4064)
			(end 0.7874 0.4064)
			(stroke
				(width 0.1524)
				(type default)
			)
			(layer "F.SilkS")
		)
		(fp_line
			(start 0.7874 0.4064)
			(end -0.7874 0.4064)
			(stroke
				(width 0.1524)
				(type default)
			)
			(layer "F.SilkS")
		)
		(fp_line
			(start -0.67945 -0.305054)
			(end -0.12065 -0.305054)
			(stroke
				(width 0.1)
				(type default)
			)
			(layer "F.Fab")
		)
		(fp_line
			(start -0.67945 0.3048)
			(end -0.67945 -0.305054)
			(stroke
				(width 0.1)
				(type default)
			)
			(layer "F.Fab")
		)
		(fp_line
			(start -0.12065 -0.305054)
			(end -0.12065 -0.2794)
			(stroke
				(width 0.1)
				(type default)
			)
			(layer "F.Fab")
		)
		(fp_line
			(start -0.12065 -0.2794)
			(end 0.12065 -0.2794)
			(stroke
				(width 0.1)
				(type default)
			)
			(layer "F.Fab")
		)
		(fp_line
			(start -0.12065 0.2794)
			(end -0.12065 0.3048)
			(stroke
				(width 0.1)
				(type default)
			)
			(layer "F.Fab")
		)
		(fp_line
			(start -0.12065 0.3048)
			(end -0.67945 0.3048)
			(stroke
				(width 0.1)
				(type default)
			)
			(layer "F.Fab")
		)
		(fp_line
			(start 0.120396 0.2794)
			(end -0.12065 0.2794)
			(stroke
				(width 0.1)
				(type default)
			)
			(layer "F.Fab")
		)
		(fp_line
			(start 0.120396 0.3048)
			(end 0.120396 0.2794)
			(stroke
				(width 0.1)
				(type default)
			)
			(layer "F.Fab")
		)
		(fp_line
			(start 0.12065 -0.3048)
			(end 0.67945 -0.3048)
			(stroke
				(width 0.1)
				(type default)
			)
			(layer "F.Fab")
		)
		(fp_line
			(start 0.12065 -0.2794)
			(end 0.12065 -0.3048)
			(stroke
				(width 0.1)
				(type default)
			)
			(layer "F.Fab")
		)
		(fp_line
			(start 0.67945 -0.3048)
			(end 0.67945 0.3048)
			(stroke
				(width 0.1)
				(type default)
			)
			(layer "F.Fab")
		)
		(fp_line
			(start 0.67945 0.3048)
			(end 0.120396 0.3048)
			(stroke
				(width 0.1)
				(type default)
			)
			(layer "F.Fab")
		)
		(pad "1" smd circle
			(at -0.40005 0)
			(size 0 0)
			(layers "F.Cu" "F.Mask" "F.Paste")
			(net "SMB_ADC_SDA")
		)
		(pad "2" smd circle
			(at 0.40005 0)
			(size 0 0)
			(layers "F.Cu" "F.Mask" "F.Paste")
			(net "SMB_ADC_SDA_R")
		)
	)
)
